(kicad_pcb
	(version 20260206)
	(generator "pcbnew")
	(generator_version "10.0")
	(general
		(thickness 1.6)
		(legacy_teardrops no)
	)
	(paper "A4")
	(title_block
		(title "Wiwynn_Tioga_Pass_MB.brd")
		(comment 1 "Tioga Pass / footprints 3018-3024 of 4770")
	)
	(layers
		(0 "F.Cu" signal "TOP")
		(4 "In1.Cu" signal "L2GND")
		(6 "In2.Cu" signal "L3")
		(8 "In3.Cu" signal "L4GND")
		(10 "In4.Cu" signal "L5")
		(12 "In5.Cu" signal "L6GND")
		(14 "In6.Cu" signal "L7VCC")
		(16 "In7.Cu" signal "L8VCC")
		(18 "In8.Cu" signal "L9GND")
		(20 "In9.Cu" signal "L10")
		(22 "In10.Cu" signal "L11GND")
		(24 "In11.Cu" signal "L12")
		(26 "In12.Cu" signal "L13GND")
		(2 "B.Cu" signal "BOTTOM")
		(9 "F.Adhes" user "F.Adhesive")
		(11 "B.Adhes" user "B.Adhesive")
		(13 "F.Paste" user "Package Geometry/Pastemask Top")
		(15 "B.Paste" user "Package Geometry/Pastemask Bottom")
		(5 "F.SilkS" user "Ref Des/Silkscreen Top")
		(7 "B.SilkS" user "Ref Des/Silkscreen Bottom")
		(1 "F.Mask" user "Board Geometry/Soldermask Top")
		(3 "B.Mask" user "Board Geometry/Soldermask Bottom")
		(17 "Dwgs.User" user "User.Drawings")
		(19 "Cmts.User" user "User.Comments")
		(21 "Eco1.User" user "User.Eco1")
		(23 "Eco2.User" user "User.Eco2")
		(25 "Edge.Cuts" user "Board Geometry/Outline")
		(27 "Margin" user)
		(31 "F.CrtYd" user "Package Geometry/Place Bound Top")
		(29 "B.CrtYd" user "Package Geometry/Place Bound Bottom")
		(35 "F.Fab" user "Ref Des/Assembly Top")
		(33 "B.Fab" user "Ref Des/Assembly Bottom")
	)
	(footprint ""
		(layer "B.Cu")
		(at 379.74905 -68.707 -90)
		(property "Reference" "C2P3"
			(at 0 0 90)
			(layer "B.SilkS")
			(hide yes)
			(effects
				(font
					(size 1.27 1.27)
				)
				(justify mirror)
			)
		)
		(property "Value" ""
			(at 0 0 90)
			(layer "B.Fab")
			(effects
				(font
					(size 1.27 1.27)
				)
				(justify mirror)
			)
		)
		(duplicate_pad_numbers_are_jumpers no)
		(fp_rect
			(start 0.2794 0.9144)
			(end -0.2794 -0.1143)
			(stroke
				(width 0)
				(type default)
			)
			(fill no)
			(layer "B.CrtYd")
		)
		(fp_line
			(start -0.2794 0.9144)
			(end 0.2794 0.9144)
			(stroke
				(width 0.1)
				(type default)
			)
			(layer "B.Fab")
		)
		(fp_line
			(start 0.2794 0.9144)
			(end 0.2794 -0.1143)
			(stroke
				(width 0.1)
				(type default)
			)
			(layer "B.Fab")
		)
		(fp_line
			(start -0.2794 -0.1143)
			(end -0.2794 0.9144)
			(stroke
				(width 0.1)
				(type default)
			)
			(layer "B.Fab")
		)
		(fp_line
			(start 0.2794 -0.1143)
			(end -0.2794 -0.1143)
			(stroke
				(width 0.1)
				(type default)
			)
			(layer "B.Fab")
		)
		(pad "1" smd custom
			(at 0 0 180)
			(size 0.10414 0.10414)
			(layers "B.Cu" "B.Mask" "B.Paste")
			(net "P3V3_STBY")
			(options
				(clearance outline)
				(anchor circle)
			)
			(primitives
				(gr_poly
					(pts
						(xy -0.20828 -0.08636) (xy -0.20828 0.08636) (xy -0.08636 0.20828) (xy 0.086614 0.20828) (xy 0.20828 0.086614)
						(xy 0.20828 -0.08636) (xy 0.08636 -0.20828) (xy -0.08636 -0.20828)
					)
					(width 0)
					(fill yes)
				)
			)
		)
		(pad "2" smd custom
			(at 0 0.8001 180)
			(size 0.10414 0.10414)
			(layers "B.Cu" "B.Mask" "B.Paste")
			(net "GND")
			(options
				(clearance outline)
				(anchor circle)
			)
			(primitives
				(gr_poly
					(pts
						(xy -0.20828 -0.08636) (xy -0.20828 0.08636) (xy -0.08636 0.20828) (xy 0.086614 0.20828) (xy 0.20828 0.086614)
						(xy 0.20828 -0.08636) (xy 0.08636 -0.20828) (xy -0.08636 -0.20828)
					)
					(width 0)
					(fill yes)
				)
			)
		)
		(zone
			(layer "B.Cu")
			(hatch none 0.5)
			(connect_pads
				(clearance 0)
			)
			(min_thickness 0.25)
			(keepout
				(tracks not_allowed)
				(vias allowed)
				(pads allowed)
				(copperpour not_allowed)
				(footprints allowed)
			)
			(placement
				(enabled no)
				(sheetname "")
			)
			(fill
				(thermal_gap 0.5)
				(thermal_bridge_width 0.5)
				(island_removal_mode 0)
			)
			(polygon
				(pts
					(xy 379.5395 -68.61937) (xy 379.1585 -68.61937) (xy 379.1585 -68.79463) (xy 379.5395 -68.794884)
				)
			)
		)
		(zone
			(layer "B.Cu")
			(hatch none 0.5)
			(connect_pads
				(clearance 0)
			)
			(min_thickness 0.25)
			(keepout
				(tracks allowed)
				(vias not_allowed)
				(pads allowed)
				(copperpour not_allowed)
				(footprints allowed)
			)
			(placement
				(enabled no)
				(sheetname "")
			)
			(fill
				(thermal_gap 0.5)
				(thermal_bridge_width 0.5)
				(island_removal_mode 0)
			)
			(polygon
				(pts
					(xy 379.5395 -68.61937) (xy 379.1585 -68.61937) (xy 379.1585 -68.79463) (xy 379.5395 -68.794884)
				)
			)
		)
	)
	(footprint ""
		(layer "B.Cu")
		(at 83.856068 -140.208 -90)
		(property "Reference" "C5G113"
			(at -1.14681 0.76708 0)
			(unlocked yes)
			(layer "B.SilkS")
			(effects
				(font
					(size 0.7874 0.5842)
					(thickness 0.1524)
				)
				(justify mirror)
			)
		)
		(property "Value" ""
			(at 0 0 90)
			(layer "B.Fab")
			(effects
				(font
					(size 1.27 1.27)
				)
				(justify mirror)
			)
		)
		(duplicate_pad_numbers_are_jumpers no)
		(fp_rect
			(start 0.4953 1.6002)
			(end -0.4953 -0.2032)
			(stroke
				(width 0)
				(type default)
			)
			(fill no)
			(layer "B.CrtYd")
		)
		(fp_line
			(start -0.4953 1.6002)
			(end 0.4953 1.6002)
			(stroke
				(width 0.1)
				(type default)
			)
			(layer "B.Fab")
		)
		(fp_line
			(start 0.4953 1.6002)
			(end 0.4953 -0.2032)
			(stroke
				(width 0.1)
				(type default)
			)
			(layer "B.Fab")
		)
		(fp_line
			(start -0.4953 -0.2032)
			(end -0.4953 1.6002)
			(stroke
				(width 0.1)
				(type default)
			)
			(layer "B.Fab")
		)
		(fp_line
			(start 0.4953 -0.2032)
			(end -0.4953 -0.2032)
			(stroke
				(width 0.1)
				(type default)
			)
			(layer "B.Fab")
		)
		(pad "1" smd rect
			(at 0 0 90)
			(size 0.762 0.889)
			(layers "B.Cu" "B.Mask" "B.Paste")
			(net "PVDDQ_KLM")
		)
		(pad "2" smd rect
			(at 0 1.397 90)
			(size 0.762 0.889)
			(layers "B.Cu" "B.Mask" "B.Paste")
			(net "GND")
		)
		(zone
			(layer "B.Cu")
			(hatch none 0.5)
			(connect_pads
				(clearance 0)
			)
			(min_thickness 0.25)
			(keepout
				(tracks not_allowed)
				(vias allowed)
				(pads allowed)
				(copperpour not_allowed)
				(footprints allowed)
			)
			(placement
				(enabled no)
				(sheetname "")
			)
			(fill
				(thermal_gap 0.5)
				(thermal_bridge_width 0.5)
				(island_removal_mode 0)
			)
			(polygon
				(pts
					(xy 82.903568 -139.827) (xy 83.411568 -139.827) (xy 83.411568 -140.589) (xy 82.903568 -140.589)
				)
			)
		)
	)
	(footprint ""
		(layer "B.Cu")
		(at 464.5025 -4.445 90)
		(property "Reference" "R2U48"
			(at 0 0 90)
			(layer "B.SilkS")
			(hide yes)
			(effects
				(font
					(size 1.27 1.27)
				)
				(justify mirror)
			)
		)
		(property "Value" ""
			(at 0 0 90)
			(layer "B.Fab")
			(effects
				(font
					(size 1.27 1.27)
				)
				(justify mirror)
			)
		)
		(duplicate_pad_numbers_are_jumpers no)
		(fp_poly
			(pts
				(xy 0.2794 -0.1016) (xy -0.2794 -0.1016) (xy -0.2794 0.9906) (xy 0.2794 0.9906)
			)
			(stroke
				(width 0)
				(type default)
			)
			(fill no)
			(layer "B.CrtYd")
		)
		(fp_line
			(start 0.2794 -0.1016)
			(end 0.2794 0.9906)
			(stroke
				(width 0.1)
				(type default)
			)
			(layer "B.Fab")
		)
		(fp_line
			(start -0.2794 -0.1016)
			(end 0.2794 -0.1016)
			(stroke
				(width 0.1)
				(type default)
			)
			(layer "B.Fab")
		)
		(fp_line
			(start 0.2794 0.9906)
			(end -0.2794 0.9906)
			(stroke
				(width 0.1)
				(type default)
			)
			(layer "B.Fab")
		)
		(fp_line
			(start -0.2794 0.9906)
			(end -0.2794 -0.1016)
			(stroke
				(width 0.1)
				(type default)
			)
			(layer "B.Fab")
		)
		(pad "1" smd rect
			(at 0 0 270)
			(size 0.508 0.508)
			(layers "B.Cu" "B.Mask" "B.Paste")
			(net "P3V3_STBY")
		)
		(pad "2" smd rect
			(at 0 0.889 270)
			(size 0.508 0.508)
			(layers "B.Cu" "B.Mask" "B.Paste")
			(net "FM_SLT_CFG2_R")
		)
		(zone
			(layer "B.Cu")
			(hatch none 0.5)
			(connect_pads
				(clearance 0)
			)
			(min_thickness 0.25)
			(keepout
				(tracks allowed)
				(vias not_allowed)
				(pads allowed)
				(copperpour not_allowed)
				(footprints allowed)
			)
			(placement
				(enabled no)
				(sheetname "")
			)
			(fill
				(thermal_gap 0.5)
				(thermal_bridge_width 0.5)
				(island_removal_mode 0)
			)
			(polygon
				(pts
					(xy 464.7565 -4.699) (xy 464.7565 -4.191) (xy 465.1375 -4.191) (xy 465.1375 -4.699)
				)
			)
		)
		(zone
			(layer "B.Cu")
			(hatch none 0.5)
			(connect_pads
				(clearance 0)
			)
			(min_thickness 0.25)
			(keepout
				(tracks not_allowed)
				(vias allowed)
				(pads allowed)
				(copperpour not_allowed)
				(footprints allowed)
			)
			(placement
				(enabled no)
				(sheetname "")
			)
			(fill
				(thermal_gap 0.5)
				(thermal_bridge_width 0.5)
				(island_removal_mode 0)
			)
			(polygon
				(pts
					(xy 465.1375 -4.699) (xy 465.1375 -4.191) (xy 464.7565 -4.191) (xy 464.7565 -4.699)
				)
			)
		)
	)
	(footprint ""
		(layer "B.Cu")
		(at 489.0008 -117.7798 -90)
		(property "Reference" "C1M5"
			(at -3.09753 4.2926 0)
			(unlocked yes)
			(layer "B.SilkS")
			(effects
				(font
					(size 0.7874 0.5842)
					(thickness 0.1524)
				)
				(justify mirror)
			)
		)
		(property "Value" ""
			(at 0 0 90)
			(layer "B.Fab")
			(effects
				(font
					(size 1.27 1.27)
				)
				(justify mirror)
			)
		)
		(duplicate_pad_numbers_are_jumpers no)
		(fp_line
			(start -2.286 7.366)
			(end -1.600708 7.366)
			(stroke
				(width 0.1524)
				(type default)
			)
			(layer "B.SilkS")
		)
		(fp_line
			(start -2.286 7.366)
			(end -2.286 1.63195)
			(stroke
				(width 0.1524)
				(type default)
			)
			(layer "B.SilkS")
		)
		(fp_line
			(start 2.286 7.366)
			(end 1.60147 7.366)
			(stroke
				(width 0.1524)
				(type default)
			)
			(layer "B.SilkS")
		)
		(fp_line
			(start 2.286 7.366)
			(end 2.286 1.632712)
			(stroke
				(width 0.1524)
				(type default)
			)
			(layer "B.SilkS")
		)
		(fp_line
			(start -2.504948 1.633728)
			(end -1.6002 1.633728)
			(stroke
				(width 0.1524)
				(type default)
			)
			(layer "B.SilkS")
		)
		(fp_line
			(start 2.563114 1.633728)
			(end 1.6002 1.633728)
			(stroke
				(width 0.1524)
				(type default)
			)
			(layer "B.SilkS")
		)
		(fp_line
			(start -2.504948 -1.616456)
			(end -2.504948 1.633728)
			(stroke
				(width 0.1524)
				(type default)
			)
			(layer "B.SilkS")
		)
		(fp_line
			(start -1.6002 -1.616456)
			(end -2.504948 -1.616456)
			(stroke
				(width 0.1524)
				(type default)
			)
			(layer "B.SilkS")
		)
		(fp_line
			(start 1.6002 -1.616456)
			(end 2.563114 -1.616456)
			(stroke
				(width 0.1524)
				(type default)
			)
			(layer "B.SilkS")
		)
		(fp_line
			(start 2.563114 -1.616456)
			(end 2.563114 1.633728)
			(stroke
				(width 0.1524)
				(type default)
			)
			(layer "B.SilkS")
		)
		(fp_rect
			(start 2.286 7.366)
			(end -2.286 -0.254)
			(stroke
				(width 0)
				(type default)
			)
			(fill no)
			(layer "B.CrtYd")
		)
		(fp_line
			(start -2.286 7.366)
			(end 2.286 7.366)
			(stroke
				(width 0.1)
				(type default)
			)
			(layer "B.Fab")
		)
		(fp_line
			(start 2.286 7.366)
			(end 2.286 -0.254)
			(stroke
				(width 0.1)
				(type default)
			)
			(layer "B.Fab")
		)
		(fp_line
			(start -2.286 -0.254)
			(end -2.286 7.366)
			(stroke
				(width 0.1)
				(type default)
			)
			(layer "B.Fab")
		)
		(fp_line
			(start 2.286 -0.254)
			(end -2.286 -0.254)
			(stroke
				(width 0.1)
				(type default)
			)
			(layer "B.Fab")
		)
		(pad "1" smd rect
			(at 0 0 90)
			(size 2.54 3.048)
			(layers "B.Cu" "B.Mask" "B.Paste")
			(net "P12V_STBY")
		)
		(pad "2" smd rect
			(at 0 7.112 90)
			(size 2.54 3.048)
			(layers "B.Cu" "B.Mask" "B.Paste")
			(net "GND")
		)
	)
	(footprint ""
		(layer "B.Cu")
		(at 335.89722 -84.82584 180)
		(property "Reference" "R3P56"
			(at 0 0 0)
			(layer "B.SilkS")
			(hide yes)
			(effects
				(font
					(size 1.27 1.27)
				)
				(justify mirror)
			)
		)
		(property "Value" ""
			(at 0 0 0)
			(layer "B.Fab")
			(effects
				(font
					(size 1.27 1.27)
				)
				(justify mirror)
			)
		)
		(duplicate_pad_numbers_are_jumpers no)
		(fp_poly
			(pts
				(xy 0.2794 -0.1016) (xy -0.2794 -0.1016) (xy -0.2794 0.9906) (xy 0.2794 0.9906)
			)
			(stroke
				(width 0)
				(type default)
			)
			(fill no)
			(layer "B.CrtYd")
		)
		(fp_line
			(start 0.2794 0.9906)
			(end -0.2794 0.9906)
			(stroke
				(width 0.1)
				(type default)
			)
			(layer "B.Fab")
		)
		(fp_line
			(start 0.2794 -0.1016)
			(end 0.2794 0.9906)
			(stroke
				(width 0.1)
				(type default)
			)
			(layer "B.Fab")
		)
		(fp_line
			(start -0.2794 0.9906)
			(end -0.2794 -0.1016)
			(stroke
				(width 0.1)
				(type default)
			)
			(layer "B.Fab")
		)
		(fp_line
			(start -0.2794 -0.1016)
			(end 0.2794 -0.1016)
			(stroke
				(width 0.1)
				(type default)
			)
			(layer "B.Fab")
		)
		(pad "1" smd rect
			(at 0 0)
			(size 0.508 0.508)
			(layers "B.Cu" "B.Mask" "B.Paste")
			(net "FM_CPU0_SM_WP")
		)
		(pad "2" smd rect
			(at 0 0.889)
			(size 0.508 0.508)
			(layers "B.Cu" "B.Mask" "B.Paste")
			(net "GND")
		)
		(zone
			(layer "B.Cu")
			(hatch none 0.5)
			(connect_pads
				(clearance 0)
			)
			(min_thickness 0.25)
			(keepout
				(tracks not_allowed)
				(vias allowed)
				(pads allowed)
				(copperpour not_allowed)
				(footprints allowed)
			)
			(placement
				(enabled no)
				(sheetname "")
			)
			(fill
				(thermal_gap 0.5)
				(thermal_bridge_width 0.5)
				(island_removal_mode 0)
			)
			(polygon
				(pts
					(xy 335.64322 -85.46084) (xy 336.15122 -85.46084) (xy 336.15122 -85.07984) (xy 335.64322 -85.07984)
				)
			)
		)
		(zone
			(layer "B.Cu")
			(hatch none 0.5)
			(connect_pads
				(clearance 0)
			)
			(min_thickness 0.25)
			(keepout
				(tracks allowed)
				(vias not_allowed)
				(pads allowed)
				(copperpour not_allowed)
				(footprints allowed)
			)
			(placement
				(enabled no)
				(sheetname "")
			)
			(fill
				(thermal_gap 0.5)
				(thermal_bridge_width 0.5)
				(island_removal_mode 0)
			)
			(polygon
				(pts
					(xy 335.64322 -85.07984) (xy 336.15122 -85.07984) (xy 336.15122 -85.46084) (xy 335.64322 -85.46084)
				)
			)
		)
	)
	(footprint ""
		(layer "B.Cu")
		(at 347.5736 -3.8608 -90)
		(property "Reference" "C3U4"
			(at 0 0 90)
			(layer "B.SilkS")
			(hide yes)
			(effects
				(font
					(size 1.27 1.27)
				)
				(justify mirror)
			)
		)
		(property "Value" ""
			(at 0 0 90)
			(layer "B.Fab")
			(effects
				(font
					(size 1.27 1.27)
				)
				(justify mirror)
			)
		)
		(duplicate_pad_numbers_are_jumpers no)
		(fp_rect
			(start 0.7239 1.9939)
			(end -0.7239 -0.2159)
			(stroke
				(width 0)
				(type default)
			)
			(fill no)
			(layer "B.CrtYd")
		)
		(fp_line
			(start -0.7239 1.9939)
			(end -0.7239 -0.2159)
			(stroke
				(width 0.1)
				(type default)
			)
			(layer "B.Fab")
		)
		(fp_line
			(start 0.7239 1.9939)
			(end -0.7239 1.9939)
			(stroke
				(width 0.1)
				(type default)
			)
			(layer "B.Fab")
		)
		(fp_line
			(start -0.7239 -0.2159)
			(end 0.7239 -0.2159)
			(stroke
				(width 0.1)
				(type default)
			)
			(layer "B.Fab")
		)
		(fp_line
			(start 0.7239 -0.2159)
			(end 0.7239 1.9939)
			(stroke
				(width 0.1)
				(type default)
			)
			(layer "B.Fab")
		)
		(pad "1" smd rect
			(at 0 0 90)
			(size 1.27 1.016)
			(layers "B.Cu" "B.Mask" "B.Paste")
			(net "VR_FET_SW_P12V_STBY_PVDDQ_ABC")
		)
		(pad "2" smd rect
			(at 0 1.778 90)
			(size 1.27 1.016)
			(layers "B.Cu" "B.Mask" "B.Paste")
			(net "GND")
		)
		(zone
			(layer "B.Cu")
			(hatch none 0.5)
			(connect_pads
				(clearance 0)
			)
			(min_thickness 0.25)
			(keepout
				(tracks not_allowed)
				(vias allowed)
				(pads allowed)
				(copperpour not_allowed)
				(footprints allowed)
			)
			(placement
				(enabled no)
				(sheetname "")
			)
			(fill
				(thermal_gap 0.5)
				(thermal_bridge_width 0.5)
				(island_removal_mode 0)
			)
			(polygon
				(pts
					(xy 346.3036 -3.2258) (xy 347.0656 -3.2258) (xy 347.0656 -4.4958) (xy 346.3036 -4.4958)
				)
			)
		)
	)
	(footprint ""
		(layer "B.Cu")
		(at 413.0675 -24.384 -90)
		(property "Reference" "C25W32"
			(at 0.8382 -0.67818 270)
			(unlocked yes)
			(layer "B.SilkS")
			(effects
				(font
					(size 0.4064 0.254)
					(thickness 0.1524)
				)
				(justify left mirror)
			)
		)
		(property "Value" ""
			(at 0 0 90)
			(layer "B.Fab")
			(effects
				(font
					(size 1.27 1.27)
				)
				(justify mirror)
			)
		)
		(duplicate_pad_numbers_are_jumpers no)
		(fp_poly
			(pts
				(xy -0.3048 -0.1016) (xy -0.3048 0.9906) (xy 0.3048 0.9906) (xy 0.3048 -0.1016)
			)
			(stroke
				(width 0)
				(type default)
			)
			(fill no)
			(layer "B.CrtYd")
		)
		(fp_line
			(start -0.3048 0.9906)
			(end -0.3048 -0.1016)
			(stroke
				(width 0.1)
				(type default)
			)
			(layer "B.Fab")
		)
		(fp_line
			(start 0.3048 0.9906)
			(end -0.3048 0.9906)
			(stroke
				(width 0.1)
				(type default)
			)
			(layer "B.Fab")
		)
		(fp_line
			(start -0.3048 -0.1016)
			(end 0.3048 -0.1016)
			(stroke
				(width 0.1)
				(type default)
			)
			(layer "B.Fab")
		)
		(fp_line
			(start 0.3048 -0.1016)
			(end 0.3048 0.9906)
			(stroke
				(width 0.1)
				(type default)
			)
			(layer "B.Fab")
		)
		(pad "1" smd rect
			(at 0 0 90)
			(size 0.508 0.508)
			(layers "B.Cu" "B.Mask" "B.Paste")
			(net "VCC_ADCAV3V3")
		)
		(pad "2" smd rect
			(at 0 0.889 90)
			(size 0.508 0.508)
			(layers "B.Cu" "B.Mask" "B.Paste")
			(net "GND")
		)
		(zone
			(layer "B.Cu")
			(hatch none 0.5)
			(connect_pads
				(clearance 0)
			)
			(min_thickness 0.25)
			(keepout
				(tracks not_allowed)
				(vias allowed)
				(pads allowed)
				(copperpour not_allowed)
				(footprints allowed)
			)
			(placement
				(enabled no)
				(sheetname "")
			)
			(fill
				(thermal_gap 0.5)
				(thermal_bridge_width 0.5)
				(island_removal_mode 0)
			)
			(polygon
				(pts
					(xy 412.4325 -24.13) (xy 412.4325 -24.638) (xy 412.8135 -24.638) (xy 412.8135 -24.13)
				)
			)
		)
		(zone
			(layer "B.Cu")
			(hatch none 0.5)
			(connect_pads
				(clearance 0)
			)
			(min_thickness 0.25)
			(keepout
				(tracks allowed)
				(vias not_allowed)
				(pads allowed)
				(copperpour not_allowed)
				(footprints allowed)
			)
			(placement
				(enabled no)
				(sheetname "")
			)
			(fill
				(thermal_gap 0.5)
				(thermal_bridge_width 0.5)
				(island_removal_mode 0)
			)
			(polygon
				(pts
					(xy 412.8135 -24.13) (xy 412.8135 -24.638) (xy 412.4325 -24.638) (xy 412.4325 -24.13)
				)
			)
		)
	)
)
